(kicad_pcb
	(version 20240108)
	(generator "pcbnew")
	(generator_version "8.0")
	(general
		(thickness 1.62)
		(legacy_teardrops no)
	)
	(paper "A4")
	(title_block
		(title "Jetson Orin Baseboard")
		(date "2025-03-12")
		(rev "1.3.4")
		(company "Antmicro Ltd")
		(comment 1 "www.antmicro.com")
		(comment 9 "footprints 488-491 of 677")
	)
	(layers
		(0 "F.Cu" signal)
		(1 "In1.Cu" signal)
		(2 "In2.Cu" signal)
		(3 "In3.Cu" signal)
		(4 "In4.Cu" jumper)
		(5 "In5.Cu" signal)
		(6 "In6.Cu" signal)
		(31 "B.Cu" signal)
		(32 "B.Adhes" user "B.Adhesive")
		(33 "F.Adhes" user "F.Adhesive")
		(34 "B.Paste" user)
		(35 "F.Paste" user)
		(36 "B.SilkS" user "B.Silkscreen")
		(37 "F.SilkS" user "F.Silkscreen")
		(38 "B.Mask" user)
		(39 "F.Mask" user)
		(40 "Dwgs.User" user "User.Drawings")
		(41 "Cmts.User" user "User.Comments")
		(42 "Eco1.User" user "User.Eco1")
		(43 "Eco2.User" user "User.Eco2")
		(44 "Edge.Cuts" user)
		(45 "Margin" user)
		(46 "B.CrtYd" user "B.Courtyard")
		(47 "F.CrtYd" user "F.Courtyard")
		(48 "B.Fab" user)
		(49 "F.Fab" user)
	)
	(footprint "antmicro-footprints:R_0402_1005Metric"
		(layer "B.Cu")
		(at 136.8 124.06)
		(descr "Resistor SMD 0402")
		(tags "resistor SMD 0402")
		(property "Reference" "R191"
			(at 1.05 -0.41 0)
			(layer "B.SilkS")
			(effects
				(font
					(size 0.7 0.7)
					(thickness 0.15)
				)
				(justify left bottom mirror)
			)
		)
		(property "Value" "R_200R_0402"
			(at 0 -1.4 180)
			(layer "B.Fab")
			(effects
				(font
					(size 0.7 0.7)
					(thickness 0.15)
				)
				(justify left bottom mirror)
			)
		)
		(property "Footprint" "antmicro-footprints:R_0402_1005Metric"
			(at 0 0 0)
			(layer "F.Fab")
			(hide yes)
			(effects
				(font
					(size 1.27 1.27)
					(thickness 0.15)
				)
			)
		)
		(property "Datasheet" "https://www.bourns.com/docs/product-datasheets/cr.pdf"
			(at 0 0 0)
			(layer "F.Fab")
			(hide yes)
			(effects
				(font
					(size 1.27 1.27)
					(thickness 0.15)
				)
			)
		)
		(property "Author" "Antmicro"
			(at 0 0 0)
			(layer "B.Fab")
			(hide yes)
			(effects
				(font
					(size 1 1)
					(thickness 0.15)
				)
				(justify mirror)
			)
		)
		(property "License" "Apache-2.0"
			(at 0 0 0)
			(layer "B.Fab")
			(hide yes)
			(effects
				(font
					(size 1 1)
					(thickness 0.15)
				)
				(justify mirror)
			)
		)
		(property "MPN" "CR0402-FX-2000GLF"
			(at 0 0 0)
			(layer "B.Fab")
			(hide yes)
			(effects
				(font
					(size 1 1)
					(thickness 0.15)
				)
				(justify mirror)
			)
		)
		(property "Manufacturer" "Bourns"
			(at 0 0 0)
			(layer "B.Fab")
			(hide yes)
			(effects
				(font
					(size 1 1)
					(thickness 0.15)
				)
				(justify mirror)
			)
		)
		(property "Tolerance" "1%"
			(at 0 0 0)
			(layer "B.Fab")
			(hide yes)
			(effects
				(font
					(size 1 1)
					(thickness 0.15)
				)
				(justify mirror)
			)
		)
		(property "Val" "200R"
			(at 0 0 0)
			(layer "B.Fab")
			(hide yes)
			(effects
				(font
					(size 1 1)
					(thickness 0.15)
				)
				(justify mirror)
			)
		)
		(sheetname "Peripherals")
		(sheetfile "peripherals.kicad_sch")
		(attr smd)
		(fp_rect
			(start -0.925 0.47)
			(end 0.925 -0.47)
			(stroke
				(width 0.05)
				(type default)
			)
			(fill none)
			(layer "B.CrtYd")
		)
		(fp_rect
			(start -0.5 0.25)
			(end 0.5 -0.25)
			(stroke
				(width 0.15)
				(type solid)
			)
			(fill none)
			(layer "B.Fab")
		)
		(fp_text user "Author: Antmicro"
			(at -0.95 -4.169 180)
			(layer "B.Fab")
			(hide yes)
			(effects
				(font
					(size 0.7 0.7)
					(thickness 0.15)
				)
				(justify left bottom mirror)
			)
		)
		(fp_text user "License: Apache-2.0"
			(at -0.95 -5.169 180)
			(layer "B.Fab")
			(hide yes)
			(effects
				(font
					(size 0.7 0.7)
					(thickness 0.15)
				)
				(justify left bottom mirror)
			)
		)
		(fp_text user "${REFERENCE}"
			(at -0.95 -3.168 180)
			(layer "B.Fab")
			(hide yes)
			(effects
				(font
					(size 0.7 0.7)
					(thickness 0.15)
				)
				(justify left bottom mirror)
			)
		)
		(pad "1" smd roundrect
			(at -0.48 0)
			(size 0.59 0.64)
			(layers "B.Cu" "B.Paste" "B.Mask")
			(roundrect_rratio 0.25)
			(net 661 "Net-(D54-A)")
			(pintype "passive")
		)
		(pad "2" smd roundrect
			(at 0.48 0)
			(size 0.59 0.64)
			(layers "B.Cu" "B.Paste" "B.Mask")
			(roundrect_rratio 0.25)
			(net 662 "/Peripherals/I2C_CONN_3V3")
			(pintype "passive")
		)
	)
	(footprint "antmicro-footprints:USON-10_2.5x1mm_P0.5mm"
		(layer "B.Cu")
		(at 53.4 119 90)
		(descr "USON-10 2.5x1mm_ Pitch 0.5mm")
		(tags "USON-10 2.5x1mm Pitch 0.5mm")
		(property "Reference" "U11"
			(at 0.8 2.4 90)
			(layer "B.SilkS")
			(effects
				(font
					(size 0.7 0.7)
					(thickness 0.15)
				)
				(justify left bottom mirror)
			)
		)
		(property "Value" "TPD4E05U06QDQARQ1"
			(at 0.018 -2.499 -90)
			(layer "B.Fab")
			(effects
				(font
					(size 0.7 0.7)
					(thickness 0.15)
				)
				(justify left bottom mirror)
			)
		)
		(property "Footprint" "antmicro-footprints:USON-10_2.5x1mm_P0.5mm"
			(at 0 0 90)
			(layer "F.Fab")
			(hide yes)
			(effects
				(font
					(size 1.27 1.27)
					(thickness 0.15)
				)
			)
		)
		(property "Datasheet" "https://www.ti.com/lit/ds/symlink/tpd4e05u06-q1.pdf?HQS=dis-mous-null-mousermode-dsf-pf-null-wwe&ts=1663591265741&ref_url=https%253A%252F%252Fwww.mouser.com%252F"
			(at 0 0 90)
			(layer "F.Fab")
			(hide yes)
			(effects
				(font
					(size 1.27 1.27)
					(thickness 0.15)
				)
			)
		)
		(property "Author" "Antmicro"
			(at 172.4 65.6 0)
			(layer "B.Fab")
			(hide yes)
			(effects
				(font
					(size 1 1)
					(thickness 0.15)
				)
				(justify mirror)
			)
		)
		(property "License" "Apache-2.0"
			(at 172.4 65.6 0)
			(layer "B.Fab")
			(hide yes)
			(effects
				(font
					(size 1 1)
					(thickness 0.15)
				)
				(justify mirror)
			)
		)
		(property "MPN" "TPD4E05U06QDQARQ1"
			(at 172.4 65.6 0)
			(layer "B.Fab")
			(hide yes)
			(effects
				(font
					(size 1 1)
					(thickness 0.15)
				)
				(justify mirror)
			)
		)
		(property "Manufacturer" "Texas Instruments"
			(at 172.4 65.6 0)
			(layer "B.Fab")
			(hide yes)
			(effects
				(font
					(size 1 1)
					(thickness 0.15)
				)
				(justify mirror)
			)
		)
		(sheetname "USB Debug, DP")
		(sheetfile "usb.kicad_sch")
		(attr smd)
		(fp_line
			(start -0.5 -1.398)
			(end 0.498 -1.398)
			(stroke
				(width 0.15)
				(type solid)
			)
			(layer "B.SilkS")
		)
		(fp_line
			(start -0.5 1.401)
			(end 0.498 1.401)
			(stroke
				(width 0.15)
				(type solid)
			)
			(layer "B.SilkS")
		)
		(fp_circle
			(center -0.68 1.27)
			(end -0.63 1.27)
			(stroke
				(width 0.15)
				(type solid)
			)
			(fill solid)
			(layer "B.SilkS")
		)
		(fp_rect
			(start -0.8 1.5)
			(end 0.8 -1.499)
			(stroke
				(width 0.05)
				(type solid)
			)
			(fill none)
			(layer "B.CrtYd")
		)
		(fp_line
			(start 0.498 -1.249)
			(end -0.5 -1.249)
			(stroke
				(width 0.15)
				(type solid)
			)
			(layer "B.Fab")
		)
		(fp_line
			(start 0.498 -1.249)
			(end 0.498 1.25)
			(stroke
				(width 0.15)
				(type solid)
			)
			(layer "B.Fab")
		)
		(fp_line
			(start -0.5 -1.249)
			(end -0.5 1)
			(stroke
				(width 0.15)
				(type solid)
			)
			(layer "B.Fab")
		)
		(fp_line
			(start -0.5 1)
			(end -0.25 1.25)
			(stroke
				(width 0.15)
				(type solid)
			)
			(layer "B.Fab")
		)
		(fp_line
			(start -0.25 1.25)
			(end 0.498 1.25)
			(stroke
				(width 0.15)
				(type solid)
			)
			(layer "B.Fab")
		)
		(fp_text user "License: Apache-2.0"
			(at -0.802 -6.9 -90)
			(layer "B.Fab")
			(hide yes)
			(effects
				(font
					(size 0.7 0.7)
					(thickness 0.15)
				)
				(justify left bottom mirror)
			)
		)
		(fp_text user "Author: Antmicro"
			(at -0.802 -5.7 -90)
			(layer "B.Fab")
			(hide yes)
			(effects
				(font
					(size 0.7 0.7)
					(thickness 0.15)
				)
				(justify left bottom mirror)
			)
		)
		(fp_text user "${REFERENCE}"
			(at -0.802 -4.498 -90)
			(layer "B.Fab")
			(hide yes)
			(effects
				(font
					(size 0.7 0.7)
					(thickness 0.15)
				)
				(justify left bottom mirror)
			)
		)
		(pad "1" smd roundrect
			(at -0.387 1 180)
			(size 0.25 0.55)
			(layers "B.Cu" "B.Paste" "B.Mask")
			(roundrect_rratio 0.25)
			(net 273 "/USB Debug, DP/USBC3_CC1")
			(pintype "passive")
		)
		(pad "2" smd roundrect
			(at -0.387 0.5 180)
			(size 0.25 0.55)
			(layers "B.Cu" "B.Paste" "B.Mask")
			(roundrect_rratio 0.25)
			(net 613 "/USB Debug, DP/USBC3_D_P")
			(pintype "passive")
		)
		(pad "3" smd roundrect
			(at -0.387 0 180)
			(size 0.4 0.55)
			(layers "B.Cu" "B.Paste" "B.Mask")
			(roundrect_rratio 0.25)
			(net 1 "GND")
			(pintype "power_in")
		)
		(pad "4" smd roundrect
			(at -0.387 -0.498 180)
			(size 0.25 0.55)
			(layers "B.Cu" "B.Paste" "B.Mask")
			(roundrect_rratio 0.25)
			(net 275 "/USB Debug, DP/USBC3_D_N")
			(pintype "passive")
		)
		(pad "5" smd roundrect
			(at -0.387 -0.998 180)
			(size 0.25 0.55)
			(layers "B.Cu" "B.Paste" "B.Mask")
			(roundrect_rratio 0.25)
			(net 276 "/USB Debug, DP/USBC3_CC2")
			(pintype "passive")
		)
		(pad "6" smd roundrect
			(at 0.385 -0.998 180)
			(size 0.25 0.55)
			(layers "B.Cu" "B.Paste" "B.Mask")
			(roundrect_rratio 0.25)
			(net 276 "/USB Debug, DP/USBC3_CC2")
			(pintype "passive")
		)
		(pad "7" smd roundrect
			(at 0.385 -0.498 180)
			(size 0.25 0.55)
			(layers "B.Cu" "B.Paste" "B.Mask")
			(roundrect_rratio 0.25)
			(net 275 "/USB Debug, DP/USBC3_D_N")
			(pintype "passive")
		)
		(pad "8" smd roundrect
			(at 0.385 0 180)
			(size 0.4 0.55)
			(layers "B.Cu" "B.Paste" "B.Mask")
			(roundrect_rratio 0.25)
			(net 1 "GND")
			(pintype "passive")
		)
		(pad "9" smd roundrect
			(at 0.385 0.5 180)
			(size 0.25 0.55)
			(layers "B.Cu" "B.Paste" "B.Mask")
			(roundrect_rratio 0.25)
			(net 613 "/USB Debug, DP/USBC3_D_P")
			(pintype "passive")
		)
		(pad "10" smd roundrect
			(at 0.385 1 180)
			(size 0.25 0.55)
			(layers "B.Cu" "B.Paste" "B.Mask")
			(roundrect_rratio 0.25)
			(net 273 "/USB Debug, DP/USBC3_CC1")
			(pintype "passive")
		)
	)
	(footprint "antmicro-footprints:TP_SMD_0.75mm"
		(layer "B.Cu")
		(at 103.175 103.55 -90)
		(property "Reference" "TP38"
			(at 0.54 -0.5 90)
			(layer "B.SilkS")
			(hide yes)
			(effects
				(font
					(size 0.7 0.7)
					(thickness 0.15)
				)
				(justify left bottom mirror)
			)
		)
		(property "Value" "TP_0.75mm_SMD"
			(at 0 -1.2 90)
			(layer "B.Fab")
			(effects
				(font
					(size 0.7 0.7)
					(thickness 0.15)
				)
				(justify left bottom mirror)
			)
		)
		(property "Footprint" "antmicro-footprints:TP_SMD_0.75mm"
			(at 0 0 -90)
			(layer "F.Fab")
			(hide yes)
			(effects
				(font
					(size 1.27 1.27)
					(thickness 0.15)
				)
			)
		)
		(property "Author" "Antmicro"
			(at -0.375 206.725 0)
			(layer "B.Fab")
			(hide yes)
			(effects
				(font
					(size 1 1)
					(thickness 0.15)
				)
				(justify mirror)
			)
		)
		(property "License" "Apache-2.0"
			(at -0.375 206.725 0)
			(layer "B.Fab")
			(hide yes)
			(effects
				(font
					(size 1 1)
					(thickness 0.15)
				)
				(justify mirror)
			)
		)
		(property "MPN" ""
			(at -0.375 206.725 0)
			(layer "B.Fab")
			(hide yes)
			(effects
				(font
					(size 1 1)
					(thickness 0.15)
				)
				(justify mirror)
			)
		)
		(property "Manufacturer" ""
			(at -0.375 206.725 0)
			(layer "B.Fab")
			(hide yes)
			(effects
				(font
					(size 1 1)
					(thickness 0.15)
				)
				(justify mirror)
			)
		)
		(sheetname "CSI")
		(sheetfile "csi.kicad_sch")
		(attr exclude_from_pos_files exclude_from_bom)
		(fp_circle
			(center 0 0)
			(end 0.475 0)
			(stroke
				(width 0.05)
				(type default)
			)
			(fill none)
			(layer "B.CrtYd")
		)
		(fp_text user "License: Apache-2.0"
			(at -0.4 -5.101 90)
			(layer "B.Fab")
			(hide yes)
			(effects
				(font
					(size 0.7 0.7)
					(thickness 0.15)
				)
				(justify left bottom mirror)
			)
		)
		(fp_text user "Author: Antmicro"
			(at -0.4 -3.901 90)
			(layer "B.Fab")
			(hide yes)
			(effects
				(font
					(size 0.7 0.7)
					(thickness 0.15)
				)
				(justify left bottom mirror)
			)
		)
		(fp_text user "${REFERENCE}"
			(at -0.4 -2.7 90)
			(layer "B.Fab")
			(hide yes)
			(effects
				(font
					(size 0.7 0.7)
					(thickness 0.15)
				)
				(justify left bottom mirror)
			)
		)
		(pad "1" smd circle
			(at 0 0 270)
			(size 0.75 0.75)
			(layers "B.Cu" "B.Mask")
			(net 537 "/CSI/MUX_I2C_5_SDA")
			(pinfunction "1")
			(pintype "passive")
		)
	)
	(footprint "antmicro-footprints:SOT-523"
		(layer "B.Cu")
		(at 65.21 73.85 90)
		(property "Reference" "Q11"
			(at -3.94 16.57 0)
			(layer "B.SilkS")
			(effects
				(font
					(size 0.7 0.7)
					(thickness 0.15)
				)
				(justify left bottom mirror)
			)
		)
		(property "Value" "PJE138K"
			(at 0.1 -1.824 -90)
			(layer "B.Fab")
			(effects
				(font
					(size 0.7 0.7)
					(thickness 0.15)
				)
				(justify left bottom mirror)
			)
		)
		(property "Footprint" "antmicro-footprints:SOT-523"
			(at 0 0 90)
			(layer "F.Fab")
			(hide yes)
			(effects
				(font
					(size 1.27 1.27)
					(thickness 0.15)
				)
			)
		)
		(property "Datasheet" "https://www.mouser.com/datasheet/2/1057/PJE138K-1876698.pdf"
			(at 0 0 90)
			(layer "F.Fab")
			(hide yes)
			(effects
				(font
					(size 1.27 1.27)
					(thickness 0.15)
				)
			)
		)
		(property "Author" "Antmicro"
			(at 139.06 8.64 0)
			(layer "B.Fab")
			(hide yes)
			(effects
				(font
					(size 1 1)
					(thickness 0.15)
				)
				(justify mirror)
			)
		)
		(property "License" "Apache-2.0"
			(at 139.06 8.64 0)
			(layer "B.Fab")
			(hide yes)
			(effects
				(font
					(size 1 1)
					(thickness 0.15)
				)
				(justify mirror)
			)
		)
		(property "MPN" "PJE138K_R1_00001"
			(at 139.06 8.64 0)
			(layer "B.Fab")
			(hide yes)
			(effects
				(font
					(size 1 1)
					(thickness 0.15)
				)
				(justify mirror)
			)
		)
		(property "Manufacturer" "PANJIT"
			(at 139.06 8.64 0)
			(layer "B.Fab")
			(hide yes)
			(effects
				(font
					(size 1 1)
					(thickness 0.15)
				)
				(justify mirror)
			)
		)
		(sheetname "Supply")
		(sheetfile "supply.kicad_sch")
		(attr smd)
		(fp_line
			(start -0.927 0.351)
			(end -0.927 0.051)
			(stroke
				(width 0.15)
				(type solid)
			)
			(layer "B.SilkS")
		)
		(fp_line
			(start -0.277 0.551)
			(end -0.725 0.551)
			(stroke
				(width 0.15)
				(type solid)
			)
			(layer "B.SilkS")
		)
		(fp_line
			(start -0.725 0.551)
			(end -0.927 0.351)
			(stroke
				(width 0.15)
				(type solid)
			)
			(layer "B.SilkS")
		)
		(fp_line
			(start -0.277 0.75)
			(end -0.277 0.551)
			(stroke
				(width 0.15)
				(type solid)
			)
			(layer "B.SilkS")
		)
		(fp_circle
			(center -0.9652 -0.9652)
			(end -0.9152 -0.9652)
			(stroke
				(width 0.15)
				(type solid)
			)
			(fill solid)
			(layer "B.SilkS")
		)
		(fp_line
			(start 1.1 -1.15)
			(end -1.12 -1.15)
			(stroke
				(width 0.05)
				(type solid)
			)
			(layer "B.CrtYd")
		)
		(fp_line
			(start 1.1 -1.15)
			(end 1.1 1.16)
			(stroke
				(width 0.05)
				(type solid)
			)
			(layer "B.CrtYd")
		)
		(fp_line
			(start -1.12 -1.15)
			(end -1.12 1.16)
			(stroke
				(width 0.05)
				(type solid)
			)
			(layer "B.CrtYd")
		)
		(fp_line
			(start 1.1 1.16)
			(end -1.12 1.16)
			(stroke
				(width 0.05)
				(type solid)
			)
			(layer "B.CrtYd")
		)
		(fp_line
			(start 0.8 -0.424)
			(end 0.8 0.425)
			(stroke
				(width 0.15)
				(type solid)
			)
			(layer "B.Fab")
		)
		(fp_line
			(start -0.802 -0.424)
			(end 0.8 -0.424)
			(stroke
				(width 0.15)
				(type solid)
			)
			(layer "B.Fab")
		)
		(fp_line
			(start -0.802 -0.424)
			(end -0.802 0.276)
			(stroke
				(width 0.15)
				(type solid)
			)
			(layer "B.Fab")
		)
		(fp_line
			(start -0.802 0.276)
			(end -0.652 0.425)
			(stroke
				(width 0.15)
				(type solid)
			)
			(layer "B.Fab")
		)
		(fp_line
			(start -0.652 0.425)
			(end 0.8 0.425)
			(stroke
				(width 0.15)
				(type solid)
			)
			(layer "B.Fab")
		)
		(fp_circle
			(center -0.9652 -0.9652)
			(end -0.9144 -0.9652)
			(stroke
				(width 0.15)
				(type solid)
			)
			(fill none)
			(layer "B.Fab")
		)
		(fp_text user "${REFERENCE}"
			(at -1.12 -3.824 -90)
			(layer "B.Fab")
			(hide yes)
			(effects
				(font
					(size 0.7 0.7)
					(thickness 0.15)
				)
				(justify left bottom mirror)
			)
		)
		(fp_text user "Author: Antmicro"
			(at -1.12 -6.224 -90)
			(layer "B.Fab")
			(hide yes)
			(effects
				(font
					(size 0.7 0.7)
					(thickness 0.15)
				)
				(justify left bottom mirror)
			)
		)
		(fp_text user "License: Apache-2.0"
			(at -1.12 -5.024 -90)
			(layer "B.Fab")
			(hide yes)
			(effects
				(font
					(size 0.7 0.7)
					(thickness 0.15)
				)
				(justify left bottom mirror)
			)
		)
		(pad "1" smd rect
			(at -0.5 -0.65 90)
			(size 0.4 0.51)
			(layers "B.Cu" "B.Paste" "B.Mask")
			(net 628 "Net-(Q11-G)")
			(pinfunction "G")
			(pintype "passive")
		)
		(pad "2" smd rect
			(at 0.498 -0.65 90)
			(size 0.4 0.51)
			(layers "B.Cu" "B.Paste" "B.Mask")
			(net 1 "GND")
			(pinfunction "S")
			(pintype "passive")
		)
		(pad "3" smd rect
			(at 0 0.652 90)
			(size 0.4 0.51)
			(layers "B.Cu" "B.Paste" "B.Mask")
			(net 629 "Net-(D37-A)")
			(pinfunction "D")
			(pintype "passive")
		)
	)
)
